(kicad_pcb
	(version 20260206)
	(generator "pcbnew")
	(generator_version "10.0")
	(general
		(thickness 1.6)
		(legacy_teardrops no)
	)
	(paper "A4")
	(title_block
		(title "Bryce Canyon_F.DPB_16315-1-OCP.brd")
		(comment 1 "Bryce Canyon / footprint 2183 of 2223 (IO2), pads 167-196 of 202")
	)
	(layers
		(0 "F.Cu" signal "TOP")
		(4 "In1.Cu" signal "L2GND")
		(6 "In2.Cu" signal "L3")
		(8 "In3.Cu" signal "L4GND")
		(10 "In4.Cu" signal "L5")
		(12 "In5.Cu" signal "L6VCC")
		(14 "In6.Cu" signal "L7VCC")
		(16 "In7.Cu" signal "L8")
		(18 "In8.Cu" signal "L9GND")
		(20 "In9.Cu" signal "L10")
		(22 "In10.Cu" signal "L11GND")
		(2 "B.Cu" signal "BOTTOM")
		(9 "F.Adhes" user "F.Adhesive")
		(11 "B.Adhes" user "B.Adhesive")
		(13 "F.Paste" user "Package Geometry/Pastemask Top")
		(15 "B.Paste" user "Package Geometry/Pastemask Bottom")
		(5 "F.SilkS" user "Ref Des/Silkscreen Top")
		(7 "B.SilkS" user "Ref Des/Silkscreen Bottom")
		(1 "F.Mask" user "Board Geometry/Soldermask Top")
		(3 "B.Mask" user "Board Geometry/Soldermask Bottom")
		(17 "Dwgs.User" user "User.Drawings")
		(19 "Cmts.User" user "User.Comments")
		(21 "Eco1.User" user "User.Eco1")
		(23 "Eco2.User" user "User.Eco2")
		(25 "Edge.Cuts" user "Board Geometry/Outline")
		(27 "Margin" user)
		(31 "F.CrtYd" user "Package Geometry/Place Bound Top")
		(29 "B.CrtYd" user "Package Geometry/Place Bound Bottom")
		(35 "F.Fab" user "Ref Des/Assembly Top")
		(33 "B.Fab" user "Ref Des/Assembly Bottom")
	)
	(footprint ""
		(layer "B.Cu")
		(at 389.349996 -30.550104 180)
		(property "Reference" "IO2"
			(at 0 0 0)
			(layer "B.SilkS")
			(hide yes)
			(effects
				(font
					(size 1.27 1.27)
				)
				(justify mirror)
			)
		)
		(property "Value" "DM-AMP-CONN200-13R-6-GP-01"
			(at 47.5488 -16.5862 180)
			(unlocked yes)
			(layer "B.Fab")
			(hide yes)
			(effects
				(font
					(size 1.016 1.016)
					(thickness 0.1524)
				)
				(justify mirror)
			)
		)
		(property "Device Type" "DMFIT-200P-384346H577-01"
			(at 47.5488 -18.1102 180)
			(unlocked yes)
			(layer "B.Fab")
			(hide yes)
			(effects
				(font
					(size 1.016 1.016)
					(thickness 0.1524)
				)
				(justify mirror)
			)
		)
		(duplicate_pad_numbers_are_jumpers no)
		(pad "GND53" thru_hole circle
			(at 26.999946 -10.700004)
			(size 0.762 0.762)
			(drill 0.359918)
			(layers "*.Cu" "*.Mask")
			(remove_unused_layers no)
			(net "GND")
			(clearance 0.1651)
			(thermal_gap 0.1651)
		)
		(pad "GND54" thru_hole circle
			(at 26.999946 -14.299946)
			(size 0.762 0.762)
			(drill 0.359918)
			(layers "*.Cu" "*.Mask")
			(remove_unused_layers no)
			(net "GND")
			(clearance 0.1651)
			(thermal_gap 0.1651)
		)
		(pad "GND55" thru_hole circle
			(at 28.800044 -2.500122)
			(size 0.762 0.762)
			(drill 0.359918)
			(layers "*.Cu" "*.Mask")
			(remove_unused_layers no)
			(net "GND")
			(clearance 0.1651)
			(thermal_gap 0.1651)
		)
		(pad "GND56" thru_hole circle
			(at 28.800044 -6.100064)
			(size 0.762 0.762)
			(drill 0.359918)
			(layers "*.Cu" "*.Mask")
			(remove_unused_layers no)
			(net "GND")
			(clearance 0.1651)
			(thermal_gap 0.1651)
		)
		(pad "GND57" thru_hole circle
			(at 28.800044 -9.700006)
			(size 0.762 0.762)
			(drill 0.359918)
			(layers "*.Cu" "*.Mask")
			(remove_unused_layers no)
			(net "GND")
			(clearance 0.1651)
			(thermal_gap 0.1651)
		)
		(pad "GND58" thru_hole circle
			(at 28.800044 -13.299948)
			(size 0.762 0.762)
			(drill 0.359918)
			(layers "*.Cu" "*.Mask")
			(remove_unused_layers no)
			(net "GND")
			(clearance 0.1651)
			(thermal_gap 0.1651)
		)
		(pad "GND59" thru_hole circle
			(at 30.599888 0.100076)
			(size 0.762 0.762)
			(drill 0.359918)
			(layers "*.Cu" "*.Mask")
			(remove_unused_layers no)
			(net "GND")
			(clearance 0.1651)
			(thermal_gap 0.1651)
		)
		(pad "GND60" thru_hole circle
			(at 30.599888 -3.50012)
			(size 0.762 0.762)
			(drill 0.359918)
			(layers "*.Cu" "*.Mask")
			(remove_unused_layers no)
			(net "GND")
			(clearance 0.1651)
			(thermal_gap 0.1651)
		)
		(pad "GND61" thru_hole circle
			(at 30.599888 -7.100062)
			(size 0.762 0.762)
			(drill 0.359918)
			(layers "*.Cu" "*.Mask")
			(remove_unused_layers no)
			(net "GND")
			(clearance 0.1651)
			(thermal_gap 0.1651)
		)
		(pad "GND62" thru_hole circle
			(at 30.599888 -10.700004)
			(size 0.762 0.762)
			(drill 0.359918)
			(layers "*.Cu" "*.Mask")
			(remove_unused_layers no)
			(net "GND")
			(clearance 0.1651)
			(thermal_gap 0.1651)
		)
		(pad "GND63" thru_hole circle
			(at 30.599888 -14.299946)
			(size 0.762 0.762)
			(drill 0.359918)
			(layers "*.Cu" "*.Mask")
			(remove_unused_layers no)
			(net "GND")
			(clearance 0.1651)
			(thermal_gap 0.1651)
		)
		(pad "GND64" thru_hole circle
			(at 32.399986 -2.500122)
			(size 0.762 0.762)
			(drill 0.359918)
			(layers "*.Cu" "*.Mask")
			(remove_unused_layers no)
			(net "GND")
			(clearance 0.1651)
			(thermal_gap 0.1651)
		)
		(pad "GND65" thru_hole circle
			(at 32.399986 -6.100064)
			(size 0.762 0.762)
			(drill 0.359918)
			(layers "*.Cu" "*.Mask")
			(remove_unused_layers no)
			(net "GND")
			(clearance 0.1651)
			(thermal_gap 0.1651)
		)
		(pad "GND66" thru_hole circle
			(at 32.399986 -9.700006)
			(size 0.762 0.762)
			(drill 0.359918)
			(layers "*.Cu" "*.Mask")
			(remove_unused_layers no)
			(net "GND")
			(clearance 0.1651)
			(thermal_gap 0.1651)
		)
		(pad "GND67" thru_hole circle
			(at 32.399986 -13.299948)
			(size 0.762 0.762)
			(drill 0.359918)
			(layers "*.Cu" "*.Mask")
			(remove_unused_layers no)
			(net "GND")
			(clearance 0.1651)
			(thermal_gap 0.1651)
		)
		(pad "GND68" thru_hole circle
			(at 34.200084 0.100076)
			(size 0.762 0.762)
			(drill 0.359918)
			(layers "*.Cu" "*.Mask")
			(remove_unused_layers no)
			(net "GND")
			(clearance 0.1651)
			(thermal_gap 0.1651)
		)
		(pad "GND69" thru_hole circle
			(at 34.200084 -3.50012)
			(size 0.762 0.762)
			(drill 0.359918)
			(layers "*.Cu" "*.Mask")
			(remove_unused_layers no)
			(net "GND")
			(clearance 0.1651)
			(thermal_gap 0.1651)
		)
		(pad "GND70" thru_hole circle
			(at 34.200084 -7.100062)
			(size 0.762 0.762)
			(drill 0.359918)
			(layers "*.Cu" "*.Mask")
			(remove_unused_layers no)
			(net "GND")
			(clearance 0.1651)
			(thermal_gap 0.1651)
		)
		(pad "GND71" thru_hole circle
			(at 34.200084 -10.700004)
			(size 0.762 0.762)
			(drill 0.359918)
			(layers "*.Cu" "*.Mask")
			(remove_unused_layers no)
			(net "GND")
			(clearance 0.1651)
			(thermal_gap 0.1651)
		)
		(pad "GND72" thru_hole circle
			(at 34.200084 -14.299946)
			(size 0.762 0.762)
			(drill 0.359918)
			(layers "*.Cu" "*.Mask")
			(remove_unused_layers no)
			(net "GND")
			(clearance 0.1651)
			(thermal_gap 0.1651)
		)
		(pad "H1" thru_hole circle
			(at 0 -12.199874)
			(size 0.664718 0.664718)
			(drill 0.359918)
			(layers "*.Cu" "*.Mask")
			(remove_unused_layers no)
			(net "PCIE_COMP_B_TO_IOM_B_8_DP")
			(clearance 0.264414)
			(padstack
				(mode custom)
				(layer "In1.Cu"
					(shape circle)
					(size 0.664718 0.664718)
					(clearance 0.264414)
				)
				(layer "In2.Cu"
					(shape circle)
					(size 0.664718 0.664718)
					(clearance 0.264414)
				)
				(layer "In3.Cu"
					(shape circle)
					(size 0.664718 0.664718)
					(clearance 0.264414)
				)
				(layer "In4.Cu"
					(shape circle)
					(size 0.664718 0.664718)
					(clearance 0.264414)
				)
				(layer "In5.Cu"
					(shape circle)
					(size 0.664718 0.664718)
					(clearance 0.264414)
				)
				(layer "In6.Cu"
					(shape circle)
					(size 0.762 0.762)
					(clearance 0.1651)
				)
				(layer "In7.Cu"
					(shape circle)
					(size 0.762 0.762)
					(clearance 0.1651)
				)
				(layer "In8.Cu"
					(shape circle)
					(size 0.762 0.762)
					(clearance 0.1651)
				)
				(layer "In9.Cu"
					(shape circle)
					(size 0.762 0.762)
					(clearance 0.1651)
				)
				(layer "In10.Cu"
					(shape circle)
					(size 0.762 0.762)
					(clearance 0.1651)
				)
				(layer "B.Cu"
					(shape circle)
					(size 0.762 0.762)
					(thermal_gap 0.1651)
					(clearance 0.1651)
				)
			)
		)
		(pad "H2" thru_hole circle
			(at 1.800098 -13.200126)
			(size 0.664718 0.664718)
			(drill 0.359918)
			(layers "*.Cu" "*.Mask")
			(remove_unused_layers no)
			(net "PCIE_COMP_B_TO_IOM_B_9_DP")
			(clearance 0.264414)
			(padstack
				(mode custom)
				(layer "In1.Cu"
					(shape circle)
					(size 0.664718 0.664718)
					(clearance 0.264414)
				)
				(layer "In2.Cu"
					(shape circle)
					(size 0.664718 0.664718)
					(clearance 0.264414)
				)
				(layer "In3.Cu"
					(shape circle)
					(size 0.664718 0.664718)
					(clearance 0.264414)
				)
				(layer "In4.Cu"
					(shape circle)
					(size 0.664718 0.664718)
					(clearance 0.264414)
				)
				(layer "In5.Cu"
					(shape circle)
					(size 0.664718 0.664718)
					(clearance 0.264414)
				)
				(layer "In6.Cu"
					(shape circle)
					(size 0.762 0.762)
					(clearance 0.1651)
				)
				(layer "In7.Cu"
					(shape circle)
					(size 0.762 0.762)
					(clearance 0.1651)
				)
				(layer "In8.Cu"
					(shape circle)
					(size 0.762 0.762)
					(clearance 0.1651)
				)
				(layer "In9.Cu"
					(shape circle)
					(size 0.762 0.762)
					(clearance 0.1651)
				)
				(layer "In10.Cu"
					(shape circle)
					(size 0.762 0.762)
					(clearance 0.1651)
				)
				(layer "B.Cu"
					(shape circle)
					(size 0.762 0.762)
					(thermal_gap 0.1651)
					(clearance 0.1651)
				)
			)
		)
		(pad "H3" thru_hole circle
			(at 3.599942 -12.199874)
			(size 0.664718 0.664718)
			(drill 0.359918)
			(layers "*.Cu" "*.Mask")
			(remove_unused_layers no)
			(net "PCIE_COMP_B_TO_IOM_B_10_DP")
			(clearance 0.264414)
			(padstack
				(mode custom)
				(layer "In1.Cu"
					(shape circle)
					(size 0.664718 0.664718)
					(clearance 0.264414)
				)
				(layer "In2.Cu"
					(shape circle)
					(size 0.664718 0.664718)
					(clearance 0.264414)
				)
				(layer "In3.Cu"
					(shape circle)
					(size 0.664718 0.664718)
					(clearance 0.264414)
				)
				(layer "In4.Cu"
					(shape circle)
					(size 0.664718 0.664718)
					(clearance 0.264414)
				)
				(layer "In5.Cu"
					(shape circle)
					(size 0.664718 0.664718)
					(clearance 0.264414)
				)
				(layer "In6.Cu"
					(shape circle)
					(size 0.762 0.762)
					(clearance 0.1651)
				)
				(layer "In7.Cu"
					(shape circle)
					(size 0.762 0.762)
					(clearance 0.1651)
				)
				(layer "In8.Cu"
					(shape circle)
					(size 0.762 0.762)
					(clearance 0.1651)
				)
				(layer "In9.Cu"
					(shape circle)
					(size 0.762 0.762)
					(clearance 0.1651)
				)
				(layer "In10.Cu"
					(shape circle)
					(size 0.762 0.762)
					(clearance 0.1651)
				)
				(layer "B.Cu"
					(shape circle)
					(size 0.762 0.762)
					(thermal_gap 0.1651)
					(clearance 0.1651)
				)
			)
		)
		(pad "H4" thru_hole circle
			(at 5.40004 -13.200126)
			(size 0.664718 0.664718)
			(drill 0.359918)
			(layers "*.Cu" "*.Mask")
			(remove_unused_layers no)
			(net "PCIE_COMP_B_TO_IOM_B_11_DP")
			(clearance 0.264414)
			(padstack
				(mode custom)
				(layer "In1.Cu"
					(shape circle)
					(size 0.664718 0.664718)
					(clearance 0.264414)
				)
				(layer "In2.Cu"
					(shape circle)
					(size 0.664718 0.664718)
					(clearance 0.264414)
				)
				(layer "In3.Cu"
					(shape circle)
					(size 0.664718 0.664718)
					(clearance 0.264414)
				)
				(layer "In4.Cu"
					(shape circle)
					(size 0.664718 0.664718)
					(clearance 0.264414)
				)
				(layer "In5.Cu"
					(shape circle)
					(size 0.664718 0.664718)
					(clearance 0.264414)
				)
				(layer "In6.Cu"
					(shape circle)
					(size 0.762 0.762)
					(clearance 0.1651)
				)
				(layer "In7.Cu"
					(shape circle)
					(size 0.762 0.762)
					(clearance 0.1651)
				)
				(layer "In8.Cu"
					(shape circle)
					(size 0.762 0.762)
					(clearance 0.1651)
				)
				(layer "In9.Cu"
					(shape circle)
					(size 0.762 0.762)
					(clearance 0.1651)
				)
				(layer "In10.Cu"
					(shape circle)
					(size 0.762 0.762)
					(clearance 0.1651)
				)
				(layer "B.Cu"
					(shape circle)
					(size 0.762 0.762)
					(thermal_gap 0.1651)
					(clearance 0.1651)
				)
			)
		)
		(pad "H5" thru_hole circle
			(at 7.199884 -12.199874)
			(size 0.664718 0.664718)
			(drill 0.359918)
			(layers "*.Cu" "*.Mask")
			(remove_unused_layers no)
			(net "PCIE_COMP_B_TO_IOM_B_12_DP")
			(clearance 0.264414)
			(padstack
				(mode custom)
				(layer "In1.Cu"
					(shape circle)
					(size 0.664718 0.664718)
					(clearance 0.264414)
				)
				(layer "In2.Cu"
					(shape circle)
					(size 0.664718 0.664718)
					(clearance 0.264414)
				)
				(layer "In3.Cu"
					(shape circle)
					(size 0.664718 0.664718)
					(clearance 0.264414)
				)
				(layer "In4.Cu"
					(shape circle)
					(size 0.664718 0.664718)
					(clearance 0.264414)
				)
				(layer "In5.Cu"
					(shape circle)
					(size 0.664718 0.664718)
					(clearance 0.264414)
				)
				(layer "In6.Cu"
					(shape circle)
					(size 0.762 0.762)
					(clearance 0.1651)
				)
				(layer "In7.Cu"
					(shape circle)
					(size 0.762 0.762)
					(clearance 0.1651)
				)
				(layer "In8.Cu"
					(shape circle)
					(size 0.762 0.762)
					(clearance 0.1651)
				)
				(layer "In9.Cu"
					(shape circle)
					(size 0.762 0.762)
					(clearance 0.1651)
				)
				(layer "In10.Cu"
					(shape circle)
					(size 0.762 0.762)
					(clearance 0.1651)
				)
				(layer "B.Cu"
					(shape circle)
					(size 0.762 0.762)
					(thermal_gap 0.1651)
					(clearance 0.1651)
				)
			)
		)
		(pad "H6" thru_hole circle
			(at 8.999982 -13.200126)
			(size 0.664718 0.664718)
			(drill 0.359918)
			(layers "*.Cu" "*.Mask")
			(remove_unused_layers no)
			(net "PCIE_COMP_B_TO_IOM_B_13_DP")
			(clearance 0.264414)
			(padstack
				(mode custom)
				(layer "In1.Cu"
					(shape circle)
					(size 0.664718 0.664718)
					(clearance 0.264414)
				)
				(layer "In2.Cu"
					(shape circle)
					(size 0.664718 0.664718)
					(clearance 0.264414)
				)
				(layer "In3.Cu"
					(shape circle)
					(size 0.664718 0.664718)
					(clearance 0.264414)
				)
				(layer "In4.Cu"
					(shape circle)
					(size 0.664718 0.664718)
					(clearance 0.264414)
				)
				(layer "In5.Cu"
					(shape circle)
					(size 0.664718 0.664718)
					(clearance 0.264414)
				)
				(layer "In6.Cu"
					(shape circle)
					(size 0.762 0.762)
					(clearance 0.1651)
				)
				(layer "In7.Cu"
					(shape circle)
					(size 0.762 0.762)
					(clearance 0.1651)
				)
				(layer "In8.Cu"
					(shape circle)
					(size 0.762 0.762)
					(clearance 0.1651)
				)
				(layer "In9.Cu"
					(shape circle)
					(size 0.762 0.762)
					(clearance 0.1651)
				)
				(layer "In10.Cu"
					(shape circle)
					(size 0.762 0.762)
					(clearance 0.1651)
				)
				(layer "B.Cu"
					(shape circle)
					(size 0.762 0.762)
					(thermal_gap 0.1651)
					(clearance 0.1651)
				)
			)
		)
		(pad "H7" thru_hole circle
			(at 10.80008 -12.199874)
			(size 0.664718 0.664718)
			(drill 0.359918)
			(layers "*.Cu" "*.Mask")
			(remove_unused_layers no)
			(net "PCIE_COMP_B_TO_IOM_B_14_DP")
			(clearance 0.264414)
			(padstack
				(mode custom)
				(layer "In1.Cu"
					(shape circle)
					(size 0.664718 0.664718)
					(clearance 0.264414)
				)
				(layer "In2.Cu"
					(shape circle)
					(size 0.664718 0.664718)
					(clearance 0.264414)
				)
				(layer "In3.Cu"
					(shape circle)
					(size 0.664718 0.664718)
					(clearance 0.264414)
				)
				(layer "In4.Cu"
					(shape circle)
					(size 0.664718 0.664718)
					(clearance 0.264414)
				)
				(layer "In5.Cu"
					(shape circle)
					(size 0.664718 0.664718)
					(clearance 0.264414)
				)
				(layer "In6.Cu"
					(shape circle)
					(size 0.762 0.762)
					(clearance 0.1651)
				)
				(layer "In7.Cu"
					(shape circle)
					(size 0.762 0.762)
					(clearance 0.1651)
				)
				(layer "In8.Cu"
					(shape circle)
					(size 0.762 0.762)
					(clearance 0.1651)
				)
				(layer "In9.Cu"
					(shape circle)
					(size 0.762 0.762)
					(clearance 0.1651)
				)
				(layer "In10.Cu"
					(shape circle)
					(size 0.762 0.762)
					(clearance 0.1651)
				)
				(layer "B.Cu"
					(shape circle)
					(size 0.762 0.762)
					(thermal_gap 0.1651)
					(clearance 0.1651)
				)
			)
		)
		(pad "H8" thru_hole circle
			(at 12.599924 -13.200126)
			(size 0.664718 0.664718)
			(drill 0.359918)
			(layers "*.Cu" "*.Mask")
			(remove_unused_layers no)
			(net "PCIE_COMP_B_TO_IOM_B_15_DP")
			(clearance 0.264414)
			(padstack
				(mode custom)
				(layer "In1.Cu"
					(shape circle)
					(size 0.664718 0.664718)
					(clearance 0.264414)
				)
				(layer "In2.Cu"
					(shape circle)
					(size 0.664718 0.664718)
					(clearance 0.264414)
				)
				(layer "In3.Cu"
					(shape circle)
					(size 0.664718 0.664718)
					(clearance 0.264414)
				)
				(layer "In4.Cu"
					(shape circle)
					(size 0.664718 0.664718)
					(clearance 0.264414)
				)
				(layer "In5.Cu"
					(shape circle)
					(size 0.664718 0.664718)
					(clearance 0.264414)
				)
				(layer "In6.Cu"
					(shape circle)
					(size 0.762 0.762)
					(clearance 0.1651)
				)
				(layer "In7.Cu"
					(shape circle)
					(size 0.762 0.762)
					(clearance 0.1651)
				)
				(layer "In8.Cu"
					(shape circle)
					(size 0.762 0.762)
					(clearance 0.1651)
				)
				(layer "In9.Cu"
					(shape circle)
					(size 0.762 0.762)
					(clearance 0.1651)
				)
				(layer "In10.Cu"
					(shape circle)
					(size 0.762 0.762)
					(clearance 0.1651)
				)
				(layer "B.Cu"
					(shape circle)
					(size 0.762 0.762)
					(thermal_gap 0.1651)
					(clearance 0.1651)
				)
			)
		)
		(pad "H9" thru_hole circle
			(at 21.599906 -12.199874)
			(size 0.664718 0.664718)
			(drill 0.359918)
			(layers "*.Cu" "*.Mask")
			(remove_unused_layers no)
			(net "PCIE_COMP_B_TO_IOM_B_23_DP")
			(clearance 0.264414)
			(padstack
				(mode custom)
				(layer "In1.Cu"
					(shape circle)
					(size 0.664718 0.664718)
					(clearance 0.264414)
				)
				(layer "In2.Cu"
					(shape circle)
					(size 0.664718 0.664718)
					(clearance 0.264414)
				)
				(layer "In3.Cu"
					(shape circle)
					(size 0.664718 0.664718)
					(clearance 0.264414)
				)
				(layer "In4.Cu"
					(shape circle)
					(size 0.664718 0.664718)
					(clearance 0.264414)
				)
				(layer "In5.Cu"
					(shape circle)
					(size 0.664718 0.664718)
					(clearance 0.264414)
				)
				(layer "In6.Cu"
					(shape circle)
					(size 0.762 0.762)
					(clearance 0.1651)
				)
				(layer "In7.Cu"
					(shape circle)
					(size 0.762 0.762)
					(clearance 0.1651)
				)
				(layer "In8.Cu"
					(shape circle)
					(size 0.762 0.762)
					(clearance 0.1651)
				)
				(layer "In9.Cu"
					(shape circle)
					(size 0.762 0.762)
					(clearance 0.1651)
				)
				(layer "In10.Cu"
					(shape circle)
					(size 0.762 0.762)
					(clearance 0.1651)
				)
				(layer "B.Cu"
					(shape circle)
					(size 0.762 0.762)
					(thermal_gap 0.1651)
					(clearance 0.1651)
				)
			)
		)
		(pad "H10" thru_hole circle
			(at 23.400004 -13.200126)
			(size 0.664718 0.664718)
			(drill 0.359918)
			(layers "*.Cu" "*.Mask")
			(remove_unused_layers no)
			(net "PCIE_COMP_B_TO_IOM_B_22_DP")
			(clearance 0.264414)
			(padstack
				(mode custom)
				(layer "In1.Cu"
					(shape circle)
					(size 0.664718 0.664718)
					(clearance 0.264414)
				)
				(layer "In2.Cu"
					(shape circle)
					(size 0.664718 0.664718)
					(clearance 0.264414)
				)
				(layer "In3.Cu"
					(shape circle)
					(size 0.664718 0.664718)
					(clearance 0.264414)
				)
				(layer "In4.Cu"
					(shape circle)
					(size 0.664718 0.664718)
					(clearance 0.264414)
				)
				(layer "In5.Cu"
					(shape circle)
					(size 0.664718 0.664718)
					(clearance 0.264414)
				)
				(layer "In6.Cu"
					(shape circle)
					(size 0.762 0.762)
					(clearance 0.1651)
				)
				(layer "In7.Cu"
					(shape circle)
					(size 0.762 0.762)
					(clearance 0.1651)
				)
				(layer "In8.Cu"
					(shape circle)
					(size 0.762 0.762)
					(clearance 0.1651)
				)
				(layer "In9.Cu"
					(shape circle)
					(size 0.762 0.762)
					(clearance 0.1651)
				)
				(layer "In10.Cu"
					(shape circle)
					(size 0.762 0.762)
					(clearance 0.1651)
				)
				(layer "B.Cu"
					(shape circle)
					(size 0.762 0.762)
					(thermal_gap 0.1651)
					(clearance 0.1651)
				)
			)
		)
	)
)
